#ISCELL
  mstr_misc dns *
  *
#ISCELL
  mstr_symbols design_note *
  *
#ISCELL
  mstr_symbols intel_corp_bpage *
  *
#ISCELL
  mstr_standard offpage *
  page205_i1
#ISCELL
  mstr_symbols pvsa_cpu0 *
  page205_i11
#CELL
  mstr_discrete capp *
  page205_i12
#ISCELL
  mstr_symbols gnd *
  page205_i13
#CELL
  mstr_discrete capp *
  page205_i14
#ISCELL
  mstr_symbols gnd *
  page205_i15
#CELL
  mstr_discrete cap *
  page205_i16
#CELL
  dev_discrete cap_a *
  page205_i18
#CELL
  mstr_discrete res *
  page205_i19
#ISCELL
  mstr_standard offpage *
  page205_i2
#CELL
  mstr_discrete cap *
  page205_i20
#ISCELL
  mstr_standard offpage *
  page205_i22
#ISCELL
  mstr_symbols pvsa_cpu0 *
  page205_i23
#CELL
  mstr_discrete res *
  page205_i24
#CELL
  mstr_discrete cap *
  page205_i25
#CELL
  mstr_discrete res *
  page205_i26
#ISCELL
  mstr_standard offpage *
  page205_i27
#ISCELL
  mstr_symbols gnd *
  page205_i28
#CELL
  mstr_discrete res *
  page205_i29
#ISCELL
  mstr_standard offpage *
  page205_i3
#CELL
  mstr_discrete res *
  page205_i30
#CELL
  dev_discrete cap_a *
  page205_i31
#CELL
  mstr_discrete cap *
  page205_i32
#CELL
  mstr_discrete cap *
  page205_i33
#CELL
  mstr_discrete cap *
  page205_i34
#CELL
  mstr_discrete cap *
  page205_i35
#ISCELL
  mstr_symbols vcc_core *
  page205_i36
#CELL
  mstr_discrete res *
  page205_i37
#ISCELL
  mstr_standard offpage *
  page205_i38
#ISCELL
  mstr_symbols gnd *
  page205_i39
#ISCELL
  mstr_symbols pvsa_cpu0 *
  page205_i4
#ISCELL
  mstr_standard offpage *
  page205_i40
#ISCELL
  mstr_standard offpage *
  page205_i41
#ISCELL
  mstr_symbols p5v_stby *
  page205_i42
#CELL
  dev_discrete cap_a *
  page205_i43
#CELL
  mstr_discrete res *
  page205_i45
#CELL
  mstr_discrete ir354xx *
  page205_i46
#CELL
  dev_discrete cap_a *
  page205_i5
#ISCELL
  mstr_symbols gnd *
  page205_i6
#CELL
  mstr_discrete res *
  page205_i62
#ISCELL
  mstr_symbols gnd *
  page205_i63
#CELL
  w_hdl sc2k2p50v3kx-gp *
  page205_i64
#CELL
  mstr_discrete cap *
  page205_i65
#ISCELL
  mstr_symbols gnd *
  page205_i66
#ISCELL
  mstr_symbols gnd *
  page205_i67
#CELL
  w_hdl 3d01r5f-gp *
  page205_i68
#CELL
  dev_discrete cap_a *
  page205_i69
#CELL
  mstr_discrete inductor *
  page205_i7
#ISCELL
  mstr_symbols gnd *
  page205_i70
#CELL
  mstr_discrete res *
  page205_i72
